(kicad_pcb
	(version 20260206)
	(generator "pcbnew")
	(generator_version "10.0")
	(general
		(thickness 1.6)
		(legacy_teardrops no)
	)
	(paper "A4")
	(title_block
		(title "01162023_DA0F0TEBIF0_F0T_Expander_BD_F_brd_V02_OCP.brd")
		(comment 1 "Grand Teton / footprints 3256-3262 of 9728")
	)
	(layers
		(0 "F.Cu" signal "TOP")
		(4 "In1.Cu" signal "GND")
		(6 "In2.Cu" signal "VCC")
		(8 "In3.Cu" signal "VCC1")
		(10 "In4.Cu" signal "GND1")
		(12 "In5.Cu" signal "IN1")
		(14 "In6.Cu" signal "GND2")
		(16 "In7.Cu" signal "IN2")
		(18 "In8.Cu" signal "GND3")
		(20 "In9.Cu" signal "IN3")
		(22 "In10.Cu" signal "GND4")
		(24 "In11.Cu" signal "IN4")
		(26 "In12.Cu" signal "GND5")
		(28 "In13.Cu" signal "IN5")
		(30 "In14.Cu" signal "GND6")
		(32 "In15.Cu" signal "IN6")
		(34 "In16.Cu" signal "GND7")
		(2 "B.Cu" signal "BOTTOM")
		(9 "F.Adhes" user "F.Adhesive")
		(11 "B.Adhes" user "B.Adhesive")
		(13 "F.Paste" user "Package Geometry/Pastemask Top")
		(15 "B.Paste" user "Package Geometry/Pastemask Bottom")
		(5 "F.SilkS" user "Ref Des/Silkscreen Top")
		(7 "B.SilkS" user "Ref Des/Silkscreen Bottom")
		(1 "F.Mask" user "Board Geometry/Soldermask Top")
		(3 "B.Mask" user "Board Geometry/Soldermask Bottom")
		(17 "Dwgs.User" user "User.Drawings")
		(19 "Cmts.User" user "User.Comments")
		(21 "Eco1.User" user "User.Eco1")
		(23 "Eco2.User" user "User.Eco2")
		(25 "Edge.Cuts" user "Board Geometry/Outline")
		(27 "Margin" user)
		(31 "F.CrtYd" user "Package Geometry/Place Bound Top")
		(29 "B.CrtYd" user "Package Geometry/Place Bound Bottom")
		(35 "F.Fab" user "Ref Des/Assembly Top")
		(33 "B.Fab" user "Ref Des/Assembly Bottom")
	)
	(footprint ""
		(layer "F.Cu")
		(at 359.85831 -254.194564)
		(property "Reference" "C834"
			(at 0 0 0)
			(layer "F.SilkS")
			(hide yes)
			(effects
				(font
					(size 1.27 1.27)
				)
			)
		)
		(property "Value" ""
			(at 0 0 0)
			(layer "F.Fab")
			(effects
				(font
					(size 1.27 1.27)
				)
			)
		)
		(duplicate_pad_numbers_are_jumpers no)
		(fp_line
			(start -0.7874 -0.4064)
			(end 0.7874 -0.4064)
			(stroke
				(width 0.1524)
				(type default)
			)
			(layer "F.SilkS")
		)
		(fp_line
			(start -0.7874 0.4064)
			(end -0.7874 -0.4064)
			(stroke
				(width 0.1524)
				(type default)
			)
			(layer "F.SilkS")
		)
		(fp_line
			(start 0.7874 -0.4064)
			(end 0.7874 0.4064)
			(stroke
				(width 0.1524)
				(type default)
			)
			(layer "F.SilkS")
		)
		(fp_line
			(start 0.7874 0.4064)
			(end -0.7874 0.4064)
			(stroke
				(width 0.1524)
				(type default)
			)
			(layer "F.SilkS")
		)
		(fp_line
			(start -0.67945 -0.305054)
			(end -0.12065 -0.305054)
			(stroke
				(width 0.1)
				(type default)
			)
			(layer "F.Fab")
		)
		(fp_line
			(start -0.67945 0.3048)
			(end -0.67945 -0.305054)
			(stroke
				(width 0.1)
				(type default)
			)
			(layer "F.Fab")
		)
		(fp_line
			(start -0.12065 -0.305054)
			(end -0.12065 -0.2794)
			(stroke
				(width 0.1)
				(type default)
			)
			(layer "F.Fab")
		)
		(fp_line
			(start -0.12065 -0.2794)
			(end 0.12065 -0.2794)
			(stroke
				(width 0.1)
				(type default)
			)
			(layer "F.Fab")
		)
		(fp_line
			(start -0.12065 0.2794)
			(end -0.12065 0.3048)
			(stroke
				(width 0.1)
				(type default)
			)
			(layer "F.Fab")
		)
		(fp_line
			(start -0.12065 0.3048)
			(end -0.67945 0.3048)
			(stroke
				(width 0.1)
				(type default)
			)
			(layer "F.Fab")
		)
		(fp_line
			(start 0.120396 0.2794)
			(end -0.12065 0.2794)
			(stroke
				(width 0.1)
				(type default)
			)
			(layer "F.Fab")
		)
		(fp_line
			(start 0.120396 0.3048)
			(end 0.120396 0.2794)
			(stroke
				(width 0.1)
				(type default)
			)
			(layer "F.Fab")
		)
		(fp_line
			(start 0.12065 -0.3048)
			(end 0.67945 -0.3048)
			(stroke
				(width 0.1)
				(type default)
			)
			(layer "F.Fab")
		)
		(fp_line
			(start 0.12065 -0.2794)
			(end 0.12065 -0.3048)
			(stroke
				(width 0.1)
				(type default)
			)
			(layer "F.Fab")
		)
		(fp_line
			(start 0.67945 -0.3048)
			(end 0.67945 0.3048)
			(stroke
				(width 0.1)
				(type default)
			)
			(layer "F.Fab")
		)
		(fp_line
			(start 0.67945 0.3048)
			(end 0.120396 0.3048)
			(stroke
				(width 0.1)
				(type default)
			)
			(layer "F.Fab")
		)
		(pad "1" smd circle
			(at -0.40005 0)
			(size 0 0)
			(layers "F.Cu" "F.Mask" "F.Paste")
			(net "P0V8_PEX2_AVRRDY")
		)
		(pad "2" smd circle
			(at 0.40005 0)
			(size 0 0)
			(layers "F.Cu" "F.Mask" "F.Paste")
			(net "GND")
		)
	)
	(footprint ""
		(layer "F.Cu")
		(at 26.162254 -262.645652 90)
		(property "Reference" "C3018"
			(at 0 0 90)
			(layer "F.SilkS")
			(hide yes)
			(effects
				(font
					(size 1.27 1.27)
				)
			)
		)
		(property "Value" ""
			(at 0 0 90)
			(layer "F.Fab")
			(effects
				(font
					(size 1.27 1.27)
				)
			)
		)
		(duplicate_pad_numbers_are_jumpers no)
		(fp_line
			(start 0.299974 -0.150114)
			(end 0.299974 0.150114)
			(stroke
				(width 0.1)
				(type default)
			)
			(layer "F.Fab")
		)
		(fp_line
			(start -0.299974 -0.150114)
			(end 0.299974 -0.150114)
			(stroke
				(width 0.1)
				(type default)
			)
			(layer "F.Fab")
		)
		(fp_line
			(start 0.299974 0.150114)
			(end -0.299974 0.150114)
			(stroke
				(width 0.1)
				(type default)
			)
			(layer "F.Fab")
		)
		(fp_line
			(start -0.299974 0.150114)
			(end -0.299974 -0.150114)
			(stroke
				(width 0.1)
				(type default)
			)
			(layer "F.Fab")
		)
		(pad "1" smd rect
			(at -0.2667 0 90)
			(size 0.3048 0.381)
			(layers "F.Cu" "F.Mask" "F.Paste")
			(net "P1V8_PLL0_PEX0")
		)
		(pad "2" smd rect
			(at 0.2667 0 90)
			(size 0.3048 0.381)
			(layers "F.Cu" "F.Mask" "F.Paste")
			(net "GND")
		)
	)
	(footprint ""
		(layer "F.Cu")
		(at 312.21934 -123.184666 180)
		(property "Reference" "C449"
			(at 0 0 180)
			(layer "F.SilkS")
			(hide yes)
			(effects
				(font
					(size 1.27 1.27)
				)
			)
		)
		(property "Value" ""
			(at 0 0 180)
			(layer "F.Fab")
			(effects
				(font
					(size 1.27 1.27)
				)
			)
		)
		(duplicate_pad_numbers_are_jumpers no)
		(fp_line
			(start 0.299974 0.150114)
			(end -0.299974 0.150114)
			(stroke
				(width 0.1)
				(type default)
			)
			(layer "F.Fab")
		)
		(fp_line
			(start 0.299974 -0.150114)
			(end 0.299974 0.150114)
			(stroke
				(width 0.1)
				(type default)
			)
			(layer "F.Fab")
		)
		(fp_line
			(start -0.299974 0.150114)
			(end -0.299974 -0.150114)
			(stroke
				(width 0.1)
				(type default)
			)
			(layer "F.Fab")
		)
		(fp_line
			(start -0.299974 -0.150114)
			(end 0.299974 -0.150114)
			(stroke
				(width 0.1)
				(type default)
			)
			(layer "F.Fab")
		)
		(pad "1" smd rect
			(at -0.2667 0 180)
			(size 0.3048 0.381)
			(layers "F.Cu" "F.Mask" "F.Paste")
			(net "P5E_PEX2_STN0_TX_DP<2>")
		)
		(pad "2" smd rect
			(at 0.2667 0 180)
			(size 0.3048 0.381)
			(layers "F.Cu" "F.Mask" "F.Paste")
			(net "P5E_PEX2_STN0_TX_C_DP<2>")
		)
	)
	(footprint ""
		(layer "F.Cu")
		(at 34.110422 -63.652146 180)
		(property "Reference" "R5841"
			(at 0 0 180)
			(layer "F.SilkS")
			(hide yes)
			(effects
				(font
					(size 1.27 1.27)
				)
			)
		)
		(property "Value" ""
			(at 0 0 180)
			(layer "F.Fab")
			(effects
				(font
					(size 1.27 1.27)
				)
			)
		)
		(duplicate_pad_numbers_are_jumpers no)
		(fp_line
			(start 0.7874 0.4064)
			(end -0.7874 0.4064)
			(stroke
				(width 0.1524)
				(type default)
			)
			(layer "F.SilkS")
		)
		(fp_line
			(start 0.7874 -0.4064)
			(end 0.7874 0.4064)
			(stroke
				(width 0.1524)
				(type default)
			)
			(layer "F.SilkS")
		)
		(fp_line
			(start -0.7874 0.4064)
			(end -0.7874 -0.4064)
			(stroke
				(width 0.1524)
				(type default)
			)
			(layer "F.SilkS")
		)
		(fp_line
			(start -0.7874 -0.4064)
			(end 0.7874 -0.4064)
			(stroke
				(width 0.1524)
				(type default)
			)
			(layer "F.SilkS")
		)
		(fp_line
			(start 0.67945 0.3048)
			(end 0.120396 0.3048)
			(stroke
				(width 0.1)
				(type default)
			)
			(layer "F.Fab")
		)
		(fp_line
			(start 0.67945 -0.3048)
			(end 0.67945 0.3048)
			(stroke
				(width 0.1)
				(type default)
			)
			(layer "F.Fab")
		)
		(fp_line
			(start 0.12065 -0.2794)
			(end 0.12065 -0.3048)
			(stroke
				(width 0.1)
				(type default)
			)
			(layer "F.Fab")
		)
		(fp_line
			(start 0.12065 -0.3048)
			(end 0.67945 -0.3048)
			(stroke
				(width 0.1)
				(type default)
			)
			(layer "F.Fab")
		)
		(fp_line
			(start 0.120396 0.3048)
			(end 0.120396 0.2794)
			(stroke
				(width 0.1)
				(type default)
			)
			(layer "F.Fab")
		)
		(fp_line
			(start 0.120396 0.2794)
			(end -0.12065 0.2794)
			(stroke
				(width 0.1)
				(type default)
			)
			(layer "F.Fab")
		)
		(fp_line
			(start -0.12065 0.3048)
			(end -0.67945 0.3048)
			(stroke
				(width 0.1)
				(type default)
			)
			(layer "F.Fab")
		)
		(fp_line
			(start -0.12065 0.2794)
			(end -0.12065 0.3048)
			(stroke
				(width 0.1)
				(type default)
			)
			(layer "F.Fab")
		)
		(fp_line
			(start -0.12065 -0.2794)
			(end 0.12065 -0.2794)
			(stroke
				(width 0.1)
				(type default)
			)
			(layer "F.Fab")
		)
		(fp_line
			(start -0.12065 -0.305054)
			(end -0.12065 -0.2794)
			(stroke
				(width 0.1)
				(type default)
			)
			(layer "F.Fab")
		)
		(fp_line
			(start -0.67945 0.3048)
			(end -0.67945 -0.305054)
			(stroke
				(width 0.1)
				(type default)
			)
			(layer "F.Fab")
		)
		(fp_line
			(start -0.67945 -0.305054)
			(end -0.12065 -0.305054)
			(stroke
				(width 0.1)
				(type default)
			)
			(layer "F.Fab")
		)
		(pad "1" smd circle
			(at -0.40005 0 180)
			(size 0 0)
			(layers "F.Cu" "F.Mask" "F.Paste")
			(net "P5V_AUX")
		)
		(pad "2" smd circle
			(at 0.40005 0 180)
			(size 0 0)
			(layers "F.Cu" "F.Mask" "F.Paste")
			(net "P12V_SSD1_PG_G2")
		)
	)
	(footprint ""
		(layer "F.Cu")
		(at 434.510942 -61.386974)
		(property "Reference" "R4510"
			(at 0 0 0)
			(layer "F.SilkS")
			(hide yes)
			(effects
				(font
					(size 1.27 1.27)
				)
			)
		)
		(property "Value" ""
			(at 0 0 0)
			(layer "F.Fab")
			(effects
				(font
					(size 1.27 1.27)
				)
			)
		)
		(duplicate_pad_numbers_are_jumpers no)
		(fp_line
			(start -0.7874 -0.4064)
			(end 0.7874 -0.4064)
			(stroke
				(width 0.1524)
				(type default)
			)
			(layer "F.SilkS")
		)
		(fp_line
			(start -0.7874 0.4064)
			(end -0.7874 -0.4064)
			(stroke
				(width 0.1524)
				(type default)
			)
			(layer "F.SilkS")
		)
		(fp_line
			(start 0.7874 -0.4064)
			(end 0.7874 0.4064)
			(stroke
				(width 0.1524)
				(type default)
			)
			(layer "F.SilkS")
		)
		(fp_line
			(start 0.7874 0.4064)
			(end -0.7874 0.4064)
			(stroke
				(width 0.1524)
				(type default)
			)
			(layer "F.SilkS")
		)
		(fp_line
			(start -0.67945 -0.305054)
			(end -0.12065 -0.305054)
			(stroke
				(width 0.1)
				(type default)
			)
			(layer "F.Fab")
		)
		(fp_line
			(start -0.67945 0.3048)
			(end -0.67945 -0.305054)
			(stroke
				(width 0.1)
				(type default)
			)
			(layer "F.Fab")
		)
		(fp_line
			(start -0.12065 -0.305054)
			(end -0.12065 -0.2794)
			(stroke
				(width 0.1)
				(type default)
			)
			(layer "F.Fab")
		)
		(fp_line
			(start -0.12065 -0.2794)
			(end 0.12065 -0.2794)
			(stroke
				(width 0.1)
				(type default)
			)
			(layer "F.Fab")
		)
		(fp_line
			(start -0.12065 0.2794)
			(end -0.12065 0.3048)
			(stroke
				(width 0.1)
				(type default)
			)
			(layer "F.Fab")
		)
		(fp_line
			(start -0.12065 0.3048)
			(end -0.67945 0.3048)
			(stroke
				(width 0.1)
				(type default)
			)
			(layer "F.Fab")
		)
		(fp_line
			(start 0.120396 0.2794)
			(end -0.12065 0.2794)
			(stroke
				(width 0.1)
				(type default)
			)
			(layer "F.Fab")
		)
		(fp_line
			(start 0.120396 0.3048)
			(end 0.120396 0.2794)
			(stroke
				(width 0.1)
				(type default)
			)
			(layer "F.Fab")
		)
		(fp_line
			(start 0.12065 -0.3048)
			(end 0.67945 -0.3048)
			(stroke
				(width 0.1)
				(type default)
			)
			(layer "F.Fab")
		)
		(fp_line
			(start 0.12065 -0.2794)
			(end 0.12065 -0.3048)
			(stroke
				(width 0.1)
				(type default)
			)
			(layer "F.Fab")
		)
		(fp_line
			(start 0.67945 -0.3048)
			(end 0.67945 0.3048)
			(stroke
				(width 0.1)
				(type default)
			)
			(layer "F.Fab")
		)
		(fp_line
			(start 0.67945 0.3048)
			(end 0.120396 0.3048)
			(stroke
				(width 0.1)
				(type default)
			)
			(layer "F.Fab")
		)
		(pad "1" smd circle
			(at -0.40005 0)
			(size 0 0)
			(layers "F.Cu" "F.Mask" "F.Paste")
			(net "PWRGD_P3V3_SSD15")
		)
		(pad "2" smd circle
			(at 0.40005 0)
			(size 0 0)
			(layers "F.Cu" "F.Mask" "F.Paste")
			(net "PWRGD_P3V3_SSD15_R")
		)
	)
	(footprint ""
		(layer "F.Cu")
		(at 98.975672 -121.509028)
		(property "Reference" "PR245"
			(at 0 0 0)
			(layer "F.SilkS")
			(hide yes)
			(effects
				(font
					(size 1.27 1.27)
				)
			)
		)
		(property "Value" ""
			(at 0 0 0)
			(layer "F.Fab")
			(effects
				(font
					(size 1.27 1.27)
				)
			)
		)
		(duplicate_pad_numbers_are_jumpers no)
		(fp_line
			(start -0.7874 -0.4064)
			(end 0.7874 -0.4064)
			(stroke
				(width 0.1524)
				(type default)
			)
			(layer "F.SilkS")
		)
		(fp_line
			(start -0.7874 0.4064)
			(end -0.7874 -0.4064)
			(stroke
				(width 0.1524)
				(type default)
			)
			(layer "F.SilkS")
		)
		(fp_line
			(start 0.7874 -0.4064)
			(end 0.7874 0.4064)
			(stroke
				(width 0.1524)
				(type default)
			)
			(layer "F.SilkS")
		)
		(fp_line
			(start 0.7874 0.4064)
			(end -0.7874 0.4064)
			(stroke
				(width 0.1524)
				(type default)
			)
			(layer "F.SilkS")
		)
		(fp_line
			(start -0.67945 -0.305054)
			(end -0.12065 -0.305054)
			(stroke
				(width 0.1)
				(type default)
			)
			(layer "F.Fab")
		)
		(fp_line
			(start -0.67945 0.3048)
			(end -0.67945 -0.305054)
			(stroke
				(width 0.1)
				(type default)
			)
			(layer "F.Fab")
		)
		(fp_line
			(start -0.12065 -0.305054)
			(end -0.12065 -0.2794)
			(stroke
				(width 0.1)
				(type default)
			)
			(layer "F.Fab")
		)
		(fp_line
			(start -0.12065 -0.2794)
			(end 0.12065 -0.2794)
			(stroke
				(width 0.1)
				(type default)
			)
			(layer "F.Fab")
		)
		(fp_line
			(start -0.12065 0.2794)
			(end -0.12065 0.3048)
			(stroke
				(width 0.1)
				(type default)
			)
			(layer "F.Fab")
		)
		(fp_line
			(start -0.12065 0.3048)
			(end -0.67945 0.3048)
			(stroke
				(width 0.1)
				(type default)
			)
			(layer "F.Fab")
		)
		(fp_line
			(start 0.120396 0.2794)
			(end -0.12065 0.2794)
			(stroke
				(width 0.1)
				(type default)
			)
			(layer "F.Fab")
		)
		(fp_line
			(start 0.120396 0.3048)
			(end 0.120396 0.2794)
			(stroke
				(width 0.1)
				(type default)
			)
			(layer "F.Fab")
		)
		(fp_line
			(start 0.12065 -0.3048)
			(end 0.67945 -0.3048)
			(stroke
				(width 0.1)
				(type default)
			)
			(layer "F.Fab")
		)
		(fp_line
			(start 0.12065 -0.2794)
			(end 0.12065 -0.3048)
			(stroke
				(width 0.1)
				(type default)
			)
			(layer "F.Fab")
		)
		(fp_line
			(start 0.67945 -0.3048)
			(end 0.67945 0.3048)
			(stroke
				(width 0.1)
				(type default)
			)
			(layer "F.Fab")
		)
		(fp_line
			(start 0.67945 0.3048)
			(end 0.120396 0.3048)
			(stroke
				(width 0.1)
				(type default)
			)
			(layer "F.Fab")
		)
		(pad "1" smd circle
			(at -0.40005 0)
			(size 0 0)
			(layers "F.Cu" "F.Mask" "F.Paste")
			(net "P3V3_NIC1_OCP")
		)
		(pad "2" smd circle
			(at 0.40005 0)
			(size 0 0)
			(layers "F.Cu" "F.Mask" "F.Paste")
			(net "GND")
		)
	)
	(footprint ""
		(layer "F.Cu")
		(at 108.601764 -224.137982 -90)
		(property "Reference" "PC295"
			(at 0 0 270)
			(layer "F.SilkS")
			(hide yes)
			(effects
				(font
					(size 1.27 1.27)
				)
			)
		)
		(property "Value" ""
			(at 0 0 270)
			(layer "F.Fab")
			(effects
				(font
					(size 1.27 1.27)
				)
			)
		)
		(duplicate_pad_numbers_are_jumpers no)
		(fp_line
			(start -0.7874 0.4064)
			(end -0.7874 -0.4064)
			(stroke
				(width 0.1524)
				(type default)
			)
			(layer "F.SilkS")
		)
		(fp_line
			(start 0.7874 0.4064)
			(end -0.7874 0.4064)
			(stroke
				(width 0.1524)
				(type default)
			)
			(layer "F.SilkS")
		)
		(fp_line
			(start -0.7874 -0.4064)
			(end 0.7874 -0.4064)
			(stroke
				(width 0.1524)
				(type default)
			)
			(layer "F.SilkS")
		)
		(fp_line
			(start 0.7874 -0.4064)
			(end 0.7874 0.4064)
			(stroke
				(width 0.1524)
				(type default)
			)
			(layer "F.SilkS")
		)
		(fp_line
			(start -0.67945 0.3048)
			(end -0.67945 -0.305054)
			(stroke
				(width 0.1)
				(type default)
			)
			(layer "F.Fab")
		)
		(fp_line
			(start -0.12065 0.3048)
			(end -0.67945 0.3048)
			(stroke
				(width 0.1)
				(type default)
			)
			(layer "F.Fab")
		)
		(fp_line
			(start 0.120396 0.3048)
			(end 0.120396 0.2794)
			(stroke
				(width 0.1)
				(type default)
			)
			(layer "F.Fab")
		)
		(fp_line
			(start 0.67945 0.3048)
			(end 0.120396 0.3048)
			(stroke
				(width 0.1)
				(type default)
			)
			(layer "F.Fab")
		)
		(fp_line
			(start -0.12065 0.2794)
			(end -0.12065 0.3048)
			(stroke
				(width 0.1)
				(type default)
			)
			(layer "F.Fab")
		)
		(fp_line
			(start 0.120396 0.2794)
			(end -0.12065 0.2794)
			(stroke
				(width 0.1)
				(type default)
			)
			(layer "F.Fab")
		)
		(fp_line
			(start -0.12065 -0.2794)
			(end 0.12065 -0.2794)
			(stroke
				(width 0.1)
				(type default)
			)
			(layer "F.Fab")
		)
		(fp_line
			(start 0.12065 -0.2794)
			(end 0.12065 -0.3048)
			(stroke
				(width 0.1)
				(type default)
			)
			(layer "F.Fab")
		)
		(fp_line
			(start 0.12065 -0.3048)
			(end 0.67945 -0.3048)
			(stroke
				(width 0.1)
				(type default)
			)
			(layer "F.Fab")
		)
		(fp_line
			(start 0.67945 -0.3048)
			(end 0.67945 0.3048)
			(stroke
				(width 0.1)
				(type default)
			)
			(layer "F.Fab")
		)
		(fp_line
			(start -0.67945 -0.305054)
			(end -0.12065 -0.305054)
			(stroke
				(width 0.1)
				(type default)
			)
			(layer "F.Fab")
		)
		(fp_line
			(start -0.12065 -0.305054)
			(end -0.12065 -0.2794)
			(stroke
				(width 0.1)
				(type default)
			)
			(layer "F.Fab")
		)
		(pad "1" smd circle
			(at -0.40005 0 270)
			(size 0 0)
			(layers "F.Cu" "F.Mask" "F.Paste")
			(net "P1V8_PEX_VCC")
		)
		(pad "2" smd circle
			(at 0.40005 0 270)
			(size 0 0)
			(layers "F.Cu" "F.Mask" "F.Paste")
			(net "GND")
		)
	)
)
